# S9S_MB_2U (Grand Teton) — schematic parts with pin connectivity, parts 5876–5876 of 6093; source: Cadence DE-HDL packaged netlist (pstxprt.dat, pstxnet.dat, pstchip.dat)

U1  SOCKET4677_AZIF0045P001C01CS  SOCKET4677_AZIF0045-P001C01CS IO  pkg SOCKET4677_82X64-5XA_H466  page 44  (pins 3598-3924 of 4677)
  EF85  VSS1406  POWER  = GND
  EF87  VSS1407  POWER  = GND
  EF89  VSS1283  POWER  = GND
  EG3  UPI1_RX_DP1  IN  = UPI_CPU0_CPU1_P0P1_DP<1>
  EG5  VSS1290  POWER  = GND
  EG7  VSS1294  POWER  = GND
  EG9  VSS1414  POWER  = GND
  EG11  PE2_RX_DP15  IN  = P5E_CPU1_PE2_RX_DP<15>
  EG13  VSS1284  POWER  = GND
  EG15  PE2_TX_DP15  OUT  = P5E_CPU1_PE2_TX_DP<15>
  EG17  RSVD160  BI  = NC_CPU1_HBM0_VIEWDIG1
  EG19  DDR5_SB_DQ15  BI  = M_F_CPU1_SB_DQ<15>
  EG21  DDR5_SB_DQS_DP6  BI  = M_F_CPU1_SB_DQS_DP<6>
  EG23  DDR5_SB_DQ10  BI  = M_F_CPU1_SB_DQ<10>
  EG25  DDR4_SB_DQ7  BI  = M_E_CPU1_SB_DQ<7>
  EG27  DDR4_SB_DQS_DP5  BI  = M_E_CPU1_SB_DQS_DP<5>
  EG29  DDR4_SB_DQ2  BI  = M_E_CPU1_SB_DQ<2>
  EG31  DDR5_SB_ECC3  BI  = M_F_CPU1_SB_CB<3>
  EG33  DDR5_SB_DQS_DP4  BI  = M_F_CPU1_SB_DQS_DP<4>
  EG35  DDR5_SB_ECC6  BI  = M_F_CPU1_SB_CB<6>
  EG37  DDR5_SB_CS_N1  OUT  = M_F_CPU1_SB_CS_N<1>
  EG39  VSS1408  POWER  = GND
  EG41  DDR5_SB_CA3  OUT  = M_F_CPU1_SB_CA<3>
  EG43  DDR4_SB_CA0  OUT  = M_E_CPU1_SB_CA<0>
  EG45  DDR4_CLK_DP0  OUT  = M_E_CPU1_CLK_DP<0>
  EG48  DDR7_A_RSP0  IN  = M_H_CPU1_SA_RSP<0>
  EG50  DDR5_SA_CA5  OUT  = M_F_CPU1_SA_CA<5>
  EG52  VSS1291  POWER  = GND
  EG54  DDR5_SA_CS_N0  OUT  = M_F_CPU1_SA_CS_N<0>
  EG56  DDR5_SA_ECC7  BI  = M_F_CPU1_SA_CB<7>
  EG58  DDR5_SA_DQS_DP9  BI  = M_F_CPU1_SA_DQS_DP<9>
  EG60  DDR5_SA_ECC2  BI  = M_F_CPU1_SA_CB<2>
  EG62  DDR5_SA_DQ23  BI  = M_F_CPU1_SA_DQ<23>
  EG64  DDR5_SA_DQS_DP7  BI  = M_F_CPU1_SA_DQS_DP<7>
  EG66  DDR5_SA_DQ18  BI  = M_F_CPU1_SA_DQ<18>
  EG68  DDR4_SA_DQ15  BI  = M_E_CPU1_SA_DQ<15>
  EG70  DDR4_SA_DQS_DP6  BI  = M_E_CPU1_SA_DQS_DP<6>
  EG72  DDR4_SA_DQ10  BI  = M_E_CPU1_SA_DQ<10>
  EG74  DDR5_SA_DQ7  BI  = M_F_CPU1_SA_DQ<7>
  EG76  DDR5_SA_DQS_DP5  BI  = M_F_CPU1_SA_DQS_DP<5>
  EG78  DDR5_SA_DQ3  BI  = M_F_CPU1_SA_DQ<3>
  EG80  VCCFA_EHV_FIVRA80  POWER  = PVCCFA_EHV_FIVRA_CPU1
  EG82  VSS1410  POWER  = GND
  EG84  VSS1411  POWER  = GND
  EG86  VSS1412  POWER  = GND
  EG88  VSS1413  POWER  = GND
  EG90  VSS1415  POWER  = GND
  EH2  UPI1_RX_DN0  IN  = UPI_CPU0_CPU1_P0P1_DN<0>
  EH4  VSS1420  POWER  = GND
  EH6  VSS1318  POWER  = GND
  EH8  DDR6_SB_DQ25  BI  = M_G_CPU1_SB_DQ<25>
  EH10  PE2_RX_DN15  IN  = P5E_CPU1_PE2_RX_DN<15>
  EH12  VSS1302  POWER  = GND
  EH14  VSS1303  POWER  = GND
  EH16  VSS1416  POWER  = GND
  EH18  VSS1305  POWER  = GND
  EH20  DDR5_SB_DQ14  BI  = M_F_CPU1_SB_DQ<14>
  EH22  DDR5_SB_DQ11  BI  = M_F_CPU1_SB_DQ<11>
  EH24  VSS1417  POWER  = GND
  EH26  DDR4_SB_DQ6  BI  = M_E_CPU1_SB_DQ<6>
  EH28  DDR4_SB_DQ3  BI  = M_E_CPU1_SB_DQ<3>
  EH30  VSS1418  POWER  = GND
  EH32  DDR5_SB_ECC2  BI  = M_F_CPU1_SB_CB<2>
  EH34  DDR5_SB_ECC7  BI  = M_F_CPU1_SB_CB<7>
  EH36  VSS1419  POWER  = GND
  EH38  DDR5_SB_CS_N0  OUT  = M_F_CPU1_SB_CS_N<0>
  EH40  DDR5_SB_CA5  OUT  = M_F_CPU1_SB_CA<5>
  EH42  VSS1312  POWER  = GND
  EH44  DDR4_SB_CA1  OUT  = M_E_CPU1_SB_CA<1>
  EH47  DDR7_A_RSP1  IN  = M_H_CPU1_SA_RSP<1>
  EH49  VSS1421  POWER  = GND
  EH51  DDR5_SA_CA3  OUT  = M_F_CPU1_SA_CA<3>
  EH53  DDR5_SA_CS_N1  OUT  = M_F_CPU1_SA_CS_N<1>
  EH55  VSS1315  POWER  = GND
  EH57  DDR5_SA_ECC6  BI  = M_F_CPU1_SA_CB<6>
  EH59  DDR5_SA_ECC3  BI  = M_F_CPU1_SA_CB<3>
  EH61  VSS1319  POWER  = GND
  EH63  DDR5_SA_DQ22  BI  = M_F_CPU1_SA_DQ<22>
  EH65  DDR5_SA_DQ19  BI  = M_F_CPU1_SA_DQ<19>
  EH67  VSS1320  POWER  = GND
  EH69  DDR4_SA_DQ14  BI  = M_E_CPU1_SA_DQ<14>
  EH71  DDR4_SA_DQ11  BI  = M_E_CPU1_SA_DQ<11>
  EH73  VSS1422  POWER  = GND
  EH75  DDR5_SA_DQ6  BI  = M_F_CPU1_SA_DQ<6>
  EH77  DDR5_SA_DQ1  BI  = M_F_CPU1_SA_DQ<1>
  EH79  VSS1322  POWER  = GND
  EH81  VSS1423  POWER  = GND
  EH83  VSS1424  POWER  = GND
  EH85  UPI3_TX_DN0  OUT  = NC
  EH87  UPI3_TX_DP4  OUT  = NC
  EH89  PE3_RX_DN0  IN  = P5E_CPU1_PE3_RX_DN<0>
  EJ3  UPI1_RX_DP0  IN  = UPI_CPU0_CPU1_P0P1_DP<0>
  EJ5  DDR6_SB_DQ29  BI  = M_G_CPU1_SB_DQ<29>
  EJ7  VSS1444  POWER  = GND
  EJ9  VSS1450  POWER  = GND
  EJ11  VSS1325  POWER  = GND
  EJ13  VSS1425  POWER  = GND
  EJ15  VCCFA_EHV_FIVRA81  POWER  = PVCCFA_EHV_FIVRA_CPU1
  EJ17  VSS1328  POWER  = GND
  EJ19  VSS1426  POWER  = GND
  EJ21  DDR5_SB_DQS_DN6  BI  = M_F_CPU1_SB_DQS_DN<6>
  EJ23  VSS1428  POWER  = GND
  EJ25  VSS1331  POWER  = GND
  EJ27  DDR4_SB_DQS_DN5  BI  = M_E_CPU1_SB_DQS_DN<5>
  EJ29  VSS1429  POWER  = GND
  EJ31  VSS1430  POWER  = GND
  EJ33  DDR5_SB_DQS_DN4  BI  = M_F_CPU1_SB_DQS_DN<4>
  EJ35  VSS1334  POWER  = GND
  EJ37  VSS1431  POWER  = GND
  EJ39  DDR5_SB_PAR  OUT  = M_F_CPU1_SB_PAR
  EJ41  VSS1432  POWER  = GND
  EJ43  VSS1433  POWER  = GND
  EJ45  DDR4_CLK_DN0  OUT  = M_E_CPU1_CLK_DN<0>
  EJ48  VSS1434  POWER  = GND
  EJ50  VSS1435  POWER  = GND
  EJ52  DDR5_SA_CA1  OUT  = M_F_CPU1_SA_CA<1>
  EJ54  VSS1340  POWER  = GND
  EJ56  VSS1439  POWER  = GND
  EJ58  DDR5_SA_DQS_DN9  BI  = M_F_CPU1_SA_DQS_DN<9>
  EJ60  VSS1442  POWER  = GND
  EJ62  VSS1343  POWER  = GND
  EJ64  DDR5_SA_DQS_DN7  BI  = M_F_CPU1_SA_DQS_DN<7>
  EJ66  VSS1443  POWER  = GND
  EJ68  VSS1345  POWER  = GND
  EJ70  DDR4_SA_DQS_DN6  BI  = M_E_CPU1_SA_DQS_DN<6>
  EJ72  VSS1347  POWER  = GND
  EJ74  VSS1447  POWER  = GND
  EJ76  DDR5_SA_DQS_DN5  BI  = M_F_CPU1_SA_DQS_DN<5>
  EJ78  VSS1448  POWER  = GND
  EJ80  UPI3_RX_DN0  IN  = GND
  EJ82  UPI3_RX_DP3  IN  = GND
  EJ84  VCCFA_EHV_FIVRA82  POWER  = PVCCFA_EHV_FIVRA_CPU1
  EJ86  UPI3_TX_DN4  OUT  = NC
  EJ88  VSS1449  POWER  = GND
  EJ90  PE3_RX_DP0  IN  = P5E_CPU1_PE3_RX_DP<0>
  EK2  VSS1458  POWER  = GND
  EK4  VSS1466  POWER  = GND
  EK6  DDR6_SB_DQ28  BI  = M_G_CPU1_SB_DQ<28>
  EK8  DDR6_SB_DQ24  BI  = M_G_CPU1_SB_DQ<24>
  EK10  VSS1451  POWER  = GND
  EK12  DDR5_SB_DQS_DP2  BI  = M_F_CPU1_SB_DQS_DP<2>
  EK14  VSS1455  POWER  = GND
  EK16  VSS1355  POWER  = GND
  EK18  DDR4_SB_DQS_DN3  BI  = M_E_CPU1_SB_DQS_DN<3>
  EK20  VSS1357  POWER  = GND
  EK22  VSS1459  POWER  = GND
  EK24  DDR4_SB_DQS_DN2  BI  = M_E_CPU1_SB_DQS_DN<2>
  EK26  VSS1359  POWER  = GND
  EK28  VSS1460  POWER  = GND
  EK30  DDR4_SB_DQS_DN1  BI  = M_E_CPU1_SB_DQS_DN<1>
  EK32  VSS1461  POWER  = GND
  EK34  VSS1463  POWER  = GND
  EK36  DDR4_SB_DQS_DN9  BI  = M_E_CPU1_SB_DQS_DN<9>
  EK38  VSS1465  POWER  = GND
  EK40  VSS1469  POWER  = GND
  EK42  DDR4_SB_CA6  OUT  = M_E_CPU1_SB_CA<6>
  EK44  VSS1366  POWER  = GND
  EK47  VSS1470  POWER  = GND
  EK49  DDR4_SA_CA2  OUT  = M_E_CPU1_SA_CA<2>
  EK51  VSS1368  POWER  = GND
  EK53  VSS1369  POWER  = GND
  EK55  DDR4_SA_DQS_DP4  BI  = M_E_CPU1_SA_DQS_DP<4>
  EK57  VSS1471  POWER  = GND
  EK59  VSS1371  POWER  = GND
  EK61  DDR4_SA_DQS_DN3  BI  = M_E_CPU1_SA_DQS_DN<3>
  EK63  VSS1372  POWER  = GND
  EK65  VSS1472  POWER  = GND
  EK67  DDR4_SA_DQS_DN2  BI  = M_E_CPU1_SA_DQS_DN<2>
  EK69  VSS1473  POWER  = GND
  EK71  VSS1375  POWER  = GND
  EK73  DDR4_SA_DQ5  BI  = M_E_CPU1_SA_DQ<5>
  EK75  VSS1474  POWER  = GND
  EK77  VSS1377  POWER  = GND
  EK79  VSS1378  POWER  = GND
  EK81  UPI3_RX_DN3  IN  = GND
  EK83  VSS1379  POWER  = GND
  EK85  UPI3_TX_DP0  OUT  = NC
  EK87  UPI3_TX_DN5  OUT  = NC
  EK89  VSS1380  POWER  = GND
  EL3  VSS1479  POWER  = GND
  EL5  VSS1486  POWER  = GND
  EL7  VSS1396  POWER  = GND
  EL9  VSS1401  POWER  = GND
  EL11  DDR5_SB_DQ20  BI  = M_F_CPU1_SB_DQ<20>
  EL13  DDR5_SB_DQ17  BI  = M_F_CPU1_SB_DQ<17>
  EL15  VSS1381  POWER  = GND
  EL17  DDR4_SB_DQ28  BI  = M_E_CPU1_SB_DQ<28>
  EL19  DDR4_SB_DQ25  BI  = M_E_CPU1_SB_DQ<25>
  EL21  VSS1475  POWER  = GND
  EL23  DDR4_SB_DQ20  BI  = M_E_CPU1_SB_DQ<20>
  EL25  DDR4_SB_DQ17  BI  = M_E_CPU1_SB_DQ<17>
  EL27  VSS1477  POWER  = GND
  EL29  DDR4_SB_DQ12  BI  = M_E_CPU1_SB_DQ<12>
  EL31  DDR4_SB_DQ9  BI  = M_E_CPU1_SB_DQ<9>
  EL33  VSS1481  POWER  = GND
  EL35  DDR4_SB_ECC0  BI  = M_E_CPU1_SB_CB<0>
  EL37  DDR4_SB_ECC5  BI  = M_E_CPU1_SB_CB<5>
  EL39  VSS1483  POWER  = GND
  EL41  DDR4_SB_CS_N3  OUT  = M_E_CPU1_SB_CS_N<3>
  EL43  DDR4_SB_CA4  OUT  = M_E_CPU1_SB_CA<4>
  EL45  VSS1485  POWER  = GND
  EL48  DDR4_SA_CA3  OUT  = M_E_CPU1_SA_CA<3>
  EL50  DDR4_SA_CS_N3  OUT  = M_E_CPU1_SA_CS_N<3>
  EL52  VSS1391  POWER  = GND
  EL54  DDR4_SA_ECC4  BI  = M_E_CPU1_SA_CB<4>
  EL56  DDR4_SA_ECC1  BI  = M_E_CPU1_SA_CB<1>
  EL58  VSS1394  POWER  = GND
  EL60  DDR4_SA_DQ28  BI  = M_E_CPU1_SA_DQ<28>
  EL62  DDR4_SA_DQ25  BI  = M_E_CPU1_SA_DQ<25>
  EL64  VSS1488  POWER  = GND
  EL66  DDR4_SA_DQ22  BI  = M_E_CPU1_SA_DQ<22>
  EL68  DDR4_SA_DQS_DP2  BI  = M_E_CPU1_SA_DQS_DP<2>
  EL70  VSS1397  POWER  = GND
  EL72  VSS1398  POWER  = GND
  EL74  DDR4_SA_DQ4  BI  = M_E_CPU1_SA_DQ<4>
  EL76  VSS1489  POWER  = GND
  EL78  DDR4_SA_DQ0  BI  = M_E_CPU1_SA_DQ<0>
  EL80  UPI3_RX_DP0  IN  = GND
  EL82  UPI3_RX_DN2  IN  = GND
  EL84  UPI3_TX_DN1  OUT  = NC
  EL86  VSS1400  POWER  = GND
  EL88  UPI3_TX_DP5  OUT  = NC
  EM4  DDR6_SB_DQ31  BI  = M_G_CPU1_SB_DQ<31>
  EM6  DDR6_SB_DQS_DN8  BI  = M_G_CPU1_SB_DQS_DN<8>
  EM8  VSS1497  POWER  = GND
  EM10  DDR5_SB_DQ21  BI  = M_F_CPU1_SB_DQ<21>
  EM12  DDR5_SB_DQS_DN2  BI  = M_F_CPU1_SB_DQS_DN<2>
  EM14  DDR5_SB_DQ16  BI  = M_F_CPU1_SB_DQ<16>
  EM16  DDR4_SB_DQ29  BI  = M_E_CPU1_SB_DQ<29>
  EM18  DDR4_SB_DQS_DP3  BI  = M_E_CPU1_SB_DQS_DP<3>
  EM20  DDR4_SB_DQ24  BI  = M_E_CPU1_SB_DQ<24>
  EM22  DDR4_SB_DQ21  BI  = M_E_CPU1_SB_DQ<21>
  EM24  DDR4_SB_DQS_DP2  BI  = M_E_CPU1_SB_DQS_DP<2>
  EM26  DDR4_SB_DQ16  BI  = M_E_CPU1_SB_DQ<16>
  EM28  DDR4_SB_DQ13  BI  = M_E_CPU1_SB_DQ<13>
  EM30  DDR4_SB_DQS_DP1  BI  = M_E_CPU1_SB_DQS_DP<1>
  EM32  DDR4_SB_DQ8  BI  = M_E_CPU1_SB_DQ<8>
  EM34  DDR4_SB_ECC1  BI  = M_E_CPU1_SB_CB<1>
  EM36  DDR4_SB_DQS_DP9  BI  = M_E_CPU1_SB_DQS_DP<9>
  EM38  DDR4_SB_ECC4  BI  = M_E_CPU1_SB_CB<4>
  EM40  DDR4_SB_CS_N2  OUT  = M_E_CPU1_SB_CS_N<2>
  EM42  VSS1492  POWER  = GND
  EM44  DDR4_SB_CA2  OUT  = M_E_CPU1_SB_CA<2>
  EM47  DDR4_SA_CA4  OUT  = M_E_CPU1_SA_CA<4>
  EM49  VSS1405  POWER  = GND
  EM51  DDR4_SA_CS_N2  OUT  = M_E_CPU1_SA_CS_N<2>
  EM53  DDR4_SA_ECC5  BI  = M_E_CPU1_SA_CB<5>
  EM55  DDR4_SA_DQS_DN4  BI  = M_E_CPU1_SA_DQS_DN<4>
  EM57  DDR4_SA_ECC0  BI  = M_E_CPU1_SA_CB<0>
  EM59  DDR4_SA_DQ29  BI  = M_E_CPU1_SA_DQ<29>
  EM61  DDR4_SA_DQS_DP3  BI  = M_E_CPU1_SA_DQS_DP<3>
  EM63  DDR4_SA_DQ24  BI  = M_E_CPU1_SA_DQ<24>
  EM65  DDR4_SA_DQ21  BI  = M_E_CPU1_SA_DQ<21>
  EM67  DDR4_SA_DQS_DP7  BI  = M_E_CPU1_SA_DQS_DP<7>
  EM69  DDR4_SA_DQ17  BI  = M_E_CPU1_SA_DQ<17>
  EM71  DDR4_SA_DQ16  BI  = M_E_CPU1_SA_DQ<16>
  EM73  VSS1496  POWER  = GND
  EM75  DDR4_SA_DQS_DN5  BI  = M_E_CPU1_SA_DQS_DN<5>
  EM77  DDR4_SA_DQ1  BI  = M_E_CPU1_SA_DQ<1>
  EM79  VSS1409  POWER  = GND
  EM81  VSS1498  POWER  = GND
  EM83  VSS1499  POWER  = GND
  EM85  UPI3_TX_DP1  OUT  = NC
  EM87  UPI3_TX_DN3  OUT  = NC
  EN5  DDR6_SB_DQS_DP8  BI  = M_G_CPU1_SB_DQS_DP<8>
  EN7  DDR6_SB_DQS_DP3  BI  = M_G_CPU1_SB_DQS_DP<3>
  EN9  VSS1446  POWER  = GND
  EN11  VSS1500  POWER  = GND
  EN13  VSS1501  POWER  = GND
  EN15  VSS1503  POWER  = GND
  EN17  VSS1505  POWER  = GND
  EN19  VSS1506  POWER  = GND
  EN21  VSS1512  POWER  = GND
  EN23  VSS1513  POWER  = GND
  EN25  VSS1515  POWER  = GND
  EN27  VSS1517  POWER  = GND
  EN29  VSS1518  POWER  = GND
  EN31  VSS1520  POWER  = GND
  EN33  VSS1522  POWER  = GND
  EN35  VSS1524  POWER  = GND
  EN37  VSS1525  POWER  = GND
  EN39  VSS1427  POWER  = GND
  EN41  VSS1526  POWER  = GND
  EN43  VSS1528  POWER  = GND
  EN45  VSS1529  POWER  = GND
  EN48  VSS1530  POWER  = GND
  EN50  VSS1531  POWER  = GND
  EN52  VSS1533  POWER  = GND
  EN54  VSS1537  POWER  = GND
  EN56  VSS1539  POWER  = GND
  EN58  VSS1436  POWER  = GND
  EN60  VSS1437  POWER  = GND
  EN62  VSS1438  POWER  = GND
  EN64  VSS1540  POWER  = GND
  EN66  VSS1440  POWER  = GND
  EN68  DDR4_SA_DQS_DN7  BI  = M_E_CPU1_SA_DQS_DN<7>
  EN70  DDR4_SA_DQ18  BI  = M_E_CPU1_SA_DQ<18>
  EN72  VSS1441  POWER  = GND
  EN74  DDR4_SA_DQS_DP5  BI  = M_E_CPU1_SA_DQS_DP<5>
  EN76  DDR4_SA_DQS_DP0  BI  = M_E_CPU1_SA_DQS_DP<0>
  EN78  VSS1541  POWER  = GND
  EN80  VSS1542  POWER  = GND
  EN82  UPI3_RX_DP2  IN  = GND
  EN84  VCCFA_EHV_FIVRA83  POWER  = PVCCFA_EHV_FIVRA_CPU1
  EN86  UPI3_TX_DP2  OUT  = NC
  EN88  VSS1445  POWER  = GND
  EP4  DDR6_SB_DQ30  BI  = M_G_CPU1_SB_DQ<30>
  EP6  DDR6_SB_DQS_DN3  BI  = M_G_CPU1_SB_DQS_DN<3>
  EP8  DDR6_SB_DQ26  BI  = M_G_CPU1_SB_DQ<26>
  EP10  DDR5_SB_DQ23  BI  = M_F_CPU1_SB_DQ<23>
  EP12  DDR5_SB_DQS_DP7  BI  = M_F_CPU1_SB_DQS_DP<7>
  EP14  DDR5_SB_DQ18  BI  = M_F_CPU1_SB_DQ<18>
  EP16  DDR4_SB_DQ31  BI  = M_E_CPU1_SB_DQ<31>
  EP18  DDR4_SB_DQS_DP8  BI  = M_E_CPU1_SB_DQS_DP<8>
  EP20  DDR4_SB_DQ26  BI  = M_E_CPU1_SB_DQ<26>
  EP22  DDR4_SB_DQ23  BI  = M_E_CPU1_SB_DQ<23>
  EP24  DDR4_SB_DQS_DP7  BI  = M_E_CPU1_SB_DQS_DP<7>
  EP26  DDR4_SB_DQ18  BI  = M_E_CPU1_SB_DQ<18>
  EP28  DDR4_SB_DQ15  BI  = M_E_CPU1_SB_DQ<15>
  EP30  DDR4_SB_DQS_DP6  BI  = M_E_CPU1_SB_DQS_DP<6>
  EP32  DDR4_SB_DQ10  BI  = M_E_CPU1_SB_DQ<10>
  EP34  DDR4_SB_ECC3  BI  = M_E_CPU1_SB_CB<3>
  EP36  DDR4_SB_DQS_DP4  BI  = M_E_CPU1_SB_DQS_DP<4>
  EP38  DDR4_SB_ECC6  BI  = M_E_CPU1_SB_CB<6>
  EP40  DDR4_SB_CS_N0  OUT  = M_E_CPU1_SB_CS_N<0>
  EP42  DDR4_SB_PAR  OUT  = M_E_CPU1_SB_PAR
  EP44  DDR4_SB_CA3  OUT  = M_E_CPU1_SB_CA<3>
